# SCM (Grand Teton) — schematic netlist excerpt (pin names and nets, part order shuffled) for the footprints in the layout excerpt that follows; sources: Cadence DE-HDL packaged netlist, KiCad conversion of 12092022_DA0F0TMDCD0_F0T_Management_Board_D_brd_V3_OCP.brd

U9  MC74VHC1G32DTT1G  IC  pkg SOT23-5_0-95_3X1-5  page 49
  IN_B  = BEEP_LED
  IN_A  = FM_ID_R_LED
  GND  = GND
  OUT_Y  = ID_LED_BUF
  VCC  = P3V3_AUX

PC208  Q_CAP  1UF 25V 10% X6S  pkg C0402  page 51 : A = P5V_AUX_VCC ; B = GND

(kicad_pcb
	(version 20260206)
	(generator "pcbnew")
	(generator_version "10.0")
	(general
		(thickness 1.6)
		(legacy_teardrops no)
	)
	(paper "A4")
	(title_block
		(title "12092022_DA0F0TMDCD0_F0T_Management_Board_D_brd_V3_OCP.brd")
		(comment 1 "Grand Teton / footprints 280-281 of 1440")
	)
	(layers
		(0 "F.Cu" signal "TOP")
		(4 "In1.Cu" signal "GND")
		(6 "In2.Cu" signal "IN1")
		(8 "In3.Cu" signal "GND1")
		(10 "In4.Cu" signal "IN2")
		(12 "In5.Cu" signal "VCC")
		(14 "In6.Cu" signal "VCC1")
		(16 "In7.Cu" signal "IN3")
		(18 "In8.Cu" signal "GND2")
		(20 "In9.Cu" signal "IN4")
		(22 "In10.Cu" signal "GND3")
		(2 "B.Cu" signal "BOTTOM")
		(9 "F.Adhes" user "F.Adhesive")
		(11 "B.Adhes" user "B.Adhesive")
		(13 "F.Paste" user "Package Geometry/Pastemask Top")
		(15 "B.Paste" user "Package Geometry/Pastemask Bottom")
		(5 "F.SilkS" user "Ref Des/Silkscreen Top")
		(7 "B.SilkS" user "Ref Des/Silkscreen Bottom")
		(1 "F.Mask" user "Board Geometry/Soldermask Top")
		(3 "B.Mask" user "Board Geometry/Soldermask Bottom")
		(17 "Dwgs.User" user "User.Drawings")
		(19 "Cmts.User" user "User.Comments")
		(21 "Eco1.User" user "User.Eco1")
		(23 "Eco2.User" user "User.Eco2")
		(25 "Edge.Cuts" user "Board Geometry/Outline")
		(27 "Margin" user)
		(31 "F.CrtYd" user "Package Geometry/Place Bound Top")
		(29 "B.CrtYd" user "Package Geometry/Place Bound Bottom")
		(35 "F.Fab" user "Ref Des/Assembly Top")
		(33 "B.Fab" user "Ref Des/Assembly Bottom")
	)
	(footprint ""
		(layer "F.Cu")
		(at 4.218432 -47.989744 90)
		(property "Reference" "PC208"
			(at 0 0 90)
			(layer "F.SilkS")
			(hide yes)
			(effects
				(font
					(size 1.27 1.27)
				)
			)
		)
		(property "Value" ""
			(at 0 0 90)
			(layer "F.Fab")
			(effects
				(font
					(size 1.27 1.27)
				)
			)
		)
		(duplicate_pad_numbers_are_jumpers no)
		(fp_line
			(start 0.7874 -0.4064)
			(end 0.7874 0.4064)
			(stroke
				(width 0.1524)
				(type default)
			)
			(layer "F.SilkS")
		)
		(fp_line
			(start -0.7874 -0.4064)
			(end 0.7874 -0.4064)
			(stroke
				(width 0.1524)
				(type default)
			)
			(layer "F.SilkS")
		)
		(fp_line
			(start 0.7874 0.4064)
			(end -0.7874 0.4064)
			(stroke
				(width 0.1524)
				(type default)
			)
			(layer "F.SilkS")
		)
		(fp_line
			(start -0.7874 0.4064)
			(end -0.7874 -0.4064)
			(stroke
				(width 0.1524)
				(type default)
			)
			(layer "F.SilkS")
		)
		(fp_line
			(start -0.12065 -0.305054)
			(end -0.12065 -0.2794)
			(stroke
				(width 0.1)
				(type default)
			)
			(layer "F.Fab")
		)
		(fp_line
			(start -0.67945 -0.305054)
			(end -0.12065 -0.305054)
			(stroke
				(width 0.1)
				(type default)
			)
			(layer "F.Fab")
		)
		(fp_line
			(start 0.67945 -0.3048)
			(end 0.67945 0.3048)
			(stroke
				(width 0.1)
				(type default)
			)
			(layer "F.Fab")
		)
		(fp_line
			(start 0.12065 -0.3048)
			(end 0.67945 -0.3048)
			(stroke
				(width 0.1)
				(type default)
			)
			(layer "F.Fab")
		)
		(fp_line
			(start 0.12065 -0.2794)
			(end 0.12065 -0.3048)
			(stroke
				(width 0.1)
				(type default)
			)
			(layer "F.Fab")
		)
		(fp_line
			(start -0.12065 -0.2794)
			(end 0.12065 -0.2794)
			(stroke
				(width 0.1)
				(type default)
			)
			(layer "F.Fab")
		)
		(fp_line
			(start 0.120396 0.2794)
			(end -0.12065 0.2794)
			(stroke
				(width 0.1)
				(type default)
			)
			(layer "F.Fab")
		)
		(fp_line
			(start -0.12065 0.2794)
			(end -0.12065 0.3048)
			(stroke
				(width 0.1)
				(type default)
			)
			(layer "F.Fab")
		)
		(fp_line
			(start 0.67945 0.3048)
			(end 0.120396 0.3048)
			(stroke
				(width 0.1)
				(type default)
			)
			(layer "F.Fab")
		)
		(fp_line
			(start 0.120396 0.3048)
			(end 0.120396 0.2794)
			(stroke
				(width 0.1)
				(type default)
			)
			(layer "F.Fab")
		)
		(fp_line
			(start -0.12065 0.3048)
			(end -0.67945 0.3048)
			(stroke
				(width 0.1)
				(type default)
			)
			(layer "F.Fab")
		)
		(fp_line
			(start -0.67945 0.3048)
			(end -0.67945 -0.305054)
			(stroke
				(width 0.1)
				(type default)
			)
			(layer "F.Fab")
		)
		(pad "1" smd circle
			(at -0.40005 0 90)
			(size 0 0)
			(layers "F.Cu" "F.Mask" "F.Paste")
			(net "P5V_AUX_VCC")
		)
		(pad "2" smd circle
			(at 0.40005 0 90)
			(size 0 0)
			(layers "F.Cu" "F.Mask" "F.Paste")
			(net "GND")
		)
	)
	(footprint ""
		(layer "F.Cu")
		(at 28.829 -13.081)
		(property "Reference" "U9"
			(at -2.38633 -0.254 90)
			(unlocked yes)
			(layer "F.SilkS")
			(effects
				(font
					(size 0.7874 0.5842)
					(thickness 0.1524)
				)
			)
		)
		(property "Value" ""
			(at 0 0 0)
			(layer "F.Fab")
			(effects
				(font
					(size 1.27 1.27)
				)
			)
		)
		(duplicate_pad_numbers_are_jumpers no)
		(fp_line
			(start -1.834896 -1.575054)
			(end -0.508 -1.575054)
			(stroke
				(width 0.1524)
				(type default)
			)
			(layer "F.SilkS")
		)
		(fp_line
			(start -1.834896 1.575054)
			(end -1.834896 -1.575054)
			(stroke
				(width 0.1524)
				(type default)
			)
			(layer "F.SilkS")
		)
		(fp_line
			(start -0.508 -1.575054)
			(end 0 -1.016)
			(stroke
				(width 0.1524)
				(type default)
			)
			(layer "F.SilkS")
		)
		(fp_line
			(start 0 -1.016)
			(end 0.508 -1.575054)
			(stroke
				(width 0.1524)
				(type default)
			)
			(layer "F.SilkS")
		)
		(fp_line
			(start 0.508 -1.575054)
			(end 1.834896 -1.575054)
			(stroke
				(width 0.1524)
				(type default)
			)
			(layer "F.SilkS")
		)
		(fp_line
			(start 1.834896 -1.575054)
			(end 1.834896 1.575054)
			(stroke
				(width 0.1524)
				(type default)
			)
			(layer "F.SilkS")
		)
		(fp_line
			(start 1.834896 1.575054)
			(end -1.834896 1.575054)
			(stroke
				(width 0.1524)
				(type default)
			)
			(layer "F.SilkS")
		)
		(fp_poly
			(pts
				(xy -2.372614 -2.627884) (xy -3.09118 -1.909318) (xy -2.013458 -1.550162)
			)
			(stroke
				(width 0)
				(type default)
			)
			(fill yes)
			(layer "F.SilkS")
		)
		(fp_line
			(start -0.824992 -1.575054)
			(end 0.824992 -1.575054)
			(stroke
				(width 0.1)
				(type default)
			)
			(layer "F.Fab")
		)
		(fp_line
			(start -0.824992 1.575054)
			(end -0.824992 -1.575054)
			(stroke
				(width 0.1)
				(type default)
			)
			(layer "F.Fab")
		)
		(fp_line
			(start 0.824992 -1.575054)
			(end 0.824992 1.575054)
			(stroke
				(width 0.1)
				(type default)
			)
			(layer "F.Fab")
		)
		(fp_line
			(start 0.824992 1.575054)
			(end -0.824992 1.575054)
			(stroke
				(width 0.1)
				(type default)
			)
			(layer "F.Fab")
		)
		(fp_poly
			(pts
				(xy -3.003296 -1.45796) (xy -3.003296 -0.44196) (xy -1.987296 -0.94996)
			)
			(stroke
				(width 0)
				(type default)
			)
			(fill yes)
			(layer "F.Fab")
		)
		(pad "1" smd rect
			(at -1.199896 -0.94996 270)
			(size 0.7112 1.016)
			(layers "F.Cu" "F.Mask" "F.Paste")
			(net "BEEP_LED")
		)
		(pad "2" smd rect
			(at -1.199896 0 270)
			(size 0.7112 1.016)
			(layers "F.Cu" "F.Mask" "F.Paste")
			(net "FM_ID_R_LED")
		)
		(pad "3" smd rect
			(at -1.199896 0.94996 270)
			(size 0.7112 1.016)
			(layers "F.Cu" "F.Mask" "F.Paste")
			(net "GND")
		)
		(pad "4" smd rect
			(at 1.199896 0.94996 270)
			(size 0.7112 1.016)
			(layers "F.Cu" "F.Mask" "F.Paste")
			(net "ID_LED_BUF")
		)
		(pad "5" smd rect
			(at 1.199896 -0.94996 270)
			(size 0.7112 1.016)
			(layers "F.Cu" "F.Mask" "F.Paste")
			(net "P3V3_AUX")
		)
	)
)
